(kicad_pcb
	(version 20260206)
	(generator "pcbnew")
	(generator_version "10.0")
	(general
		(thickness 1.6)
		(legacy_teardrops no)
	)
	(paper "A4")
	(title_block
		(title "04192023_DAF0TMB3IC0_F0TG_MB_C_brd_V02_OCP.brd")
		(comment 1 "Grand Teton / footprint 3955 of 8354 (U25), pads 1538-1647 of 6102")
	)
	(layers
		(0 "F.Cu" signal "TOP")
		(4 "In1.Cu" signal "GND")
		(6 "In2.Cu" signal "IN1")
		(8 "In3.Cu" signal "GND1")
		(10 "In4.Cu" signal "IN2")
		(12 "In5.Cu" signal "GND2")
		(14 "In6.Cu" signal "IN3")
		(16 "In7.Cu" signal "GND3")
		(18 "In8.Cu" signal "VCC")
		(20 "In9.Cu" signal "VCC1")
		(22 "In10.Cu" signal "GND4")
		(24 "In11.Cu" signal "IN4")
		(26 "In12.Cu" signal "GND5")
		(28 "In13.Cu" signal "IN5")
		(30 "In14.Cu" signal "GND6")
		(32 "In15.Cu" signal "IN6")
		(34 "In16.Cu" signal "GND7")
		(2 "B.Cu" signal "BOTTOM")
		(9 "F.Adhes" user "F.Adhesive")
		(11 "B.Adhes" user "B.Adhesive")
		(13 "F.Paste" user "Package Geometry/Pastemask Top")
		(15 "B.Paste" user "Package Geometry/Pastemask Bottom")
		(5 "F.SilkS" user "Ref Des/Silkscreen Top")
		(7 "B.SilkS" user "Ref Des/Silkscreen Bottom")
		(1 "F.Mask" user "Board Geometry/Soldermask Top")
		(3 "B.Mask" user "Board Geometry/Soldermask Bottom")
		(17 "Dwgs.User" user "User.Drawings")
		(19 "Cmts.User" user "User.Comments")
		(21 "Eco1.User" user "User.Eco1")
		(23 "Eco2.User" user "User.Eco2")
		(25 "Edge.Cuts" user "Board Geometry/Outline")
		(27 "Margin" user)
		(31 "F.CrtYd" user "Package Geometry/Place Bound Top")
		(29 "B.CrtYd" user "Package Geometry/Place Bound Bottom")
		(35 "F.Fab" user "Ref Des/Assembly Top")
		(33 "B.Fab" user "Ref Des/Assembly Bottom")
	)
	(footprint ""
		(layer "F.Cu")
		(at 359.867962 -258.880102 180)
		(property "Reference" "U25"
			(at -45.78477 -62.086744 0)
			(unlocked yes)
			(layer "F.SilkS")
			(effects
				(font
					(size 0.7874 0.5842)
					(thickness 0.1524)
				)
			)
		)
		(property "Value" ""
			(at 0 0 180)
			(layer "F.Fab")
			(effects
				(font
					(size 1.27 1.27)
				)
			)
		)
		(duplicate_pad_numbers_are_jumpers no)
		(pad "B73" smd circle
			(at 33.049972 -35.999928 180)
			(size 0.450088 0.450088)
			(layers "F.Cu" "F.Mask" "F.Paste")
			(net "VSENSE_PVDD18_S5_P0_DN")
		)
		(pad "BA1" smd circle
			(at -34.159952 -4.409948 180)
			(size 0.450088 0.450088)
			(layers "F.Cu" "F.Mask" "F.Paste")
			(net "GND")
		)
		(pad "BA2" smd circle
			(at -33.219898 -4.409948 180)
			(size 0.450088 0.450088)
			(layers "F.Cu" "F.Mask" "F.Paste")
			(net "M_G_CPU0_SA_CA<4>")
		)
		(pad "BA3" smd circle
			(at -32.280098 -4.409948 180)
			(size 0.450088 0.450088)
			(layers "F.Cu" "F.Mask" "F.Paste")
			(net "M_G_CPU0_SA_CA<3>")
		)
		(pad "BA4" smd circle
			(at -31.340044 -4.409948 180)
			(size 0.450088 0.450088)
			(layers "F.Cu" "F.Mask" "F.Paste")
			(net "PVDDCR_SOC_P0")
		)
		(pad "BA5" smd circle
			(at -30.39999 -4.409948 180)
			(size 0.450088 0.450088)
			(layers "F.Cu" "F.Mask" "F.Paste")
			(net "M_K_CPU0_SA_CA<4>")
		)
		(pad "BA6" smd circle
			(at -29.459936 -4.409948 180)
			(size 0.450088 0.450088)
			(layers "F.Cu" "F.Mask" "F.Paste")
			(net "GND")
		)
		(pad "BA7" smd circle
			(at -28.519882 -4.409948 180)
			(size 0.450088 0.450088)
			(layers "F.Cu" "F.Mask" "F.Paste")
			(net "M_K_CPU0_SA_CA<3>")
		)
		(pad "BA8" smd circle
			(at -27.580082 -4.409948 180)
			(size 0.450088 0.450088)
			(layers "F.Cu" "F.Mask" "F.Paste")
			(net "GND")
		)
		(pad "BA9" smd circle
			(at -26.640028 -4.409948 180)
			(size 0.450088 0.450088)
			(layers "F.Cu" "F.Mask" "F.Paste")
			(net "M_L_CPU0_SA_CA<4>")
		)
		(pad "BA10" smd circle
			(at -25.699974 -4.409948 180)
			(size 0.450088 0.450088)
			(layers "F.Cu" "F.Mask" "F.Paste")
			(net "M_L_CPU0_SA_CA<3>")
		)
		(pad "BA11" smd circle
			(at -24.75992 -4.409948 180)
			(size 0.450088 0.450088)
			(layers "F.Cu" "F.Mask" "F.Paste")
			(net "PVDDCR_SOC_P0")
		)
		(pad "BA12" smd circle
			(at -23.82012 -4.409948 180)
			(size 0.450088 0.450088)
			(layers "F.Cu" "F.Mask" "F.Paste")
			(net "M_H_CPU0_SA_CA<4>")
		)
		(pad "BA13" smd circle
			(at -22.880066 -4.409948 180)
			(size 0.450088 0.450088)
			(layers "F.Cu" "F.Mask" "F.Paste")
			(net "GND")
		)
		(pad "BA14" smd circle
			(at -21.940012 -4.409948 180)
			(size 0.450088 0.450088)
			(layers "F.Cu" "F.Mask" "F.Paste")
			(net "M_H_CPU0_SA_CA<3>")
		)
		(pad "BA15" smd circle
			(at -20.999958 -4.409948 180)
			(size 0.450088 0.450088)
			(layers "F.Cu" "F.Mask" "F.Paste")
			(net "GND")
		)
		(pad "BA16" smd circle
			(at -20.059904 -4.409948 180)
			(size 0.450088 0.450088)
			(layers "F.Cu" "F.Mask" "F.Paste")
			(net "M_J_CPU0_SA_CA<4>")
		)
		(pad "BA17" smd circle
			(at -19.120104 -4.409948 180)
			(size 0.450088 0.450088)
			(layers "F.Cu" "F.Mask" "F.Paste")
			(net "M_J_CPU0_SA_CA<3>")
		)
		(pad "BA18" smd circle
			(at -18.18005 -4.409948 180)
			(size 0.450088 0.450088)
			(layers "F.Cu" "F.Mask" "F.Paste")
			(net "PVDDCR_SOC_P0")
		)
		(pad "BA19" smd circle
			(at -17.239996 -4.409948 180)
			(size 0.450088 0.450088)
			(layers "F.Cu" "F.Mask" "F.Paste")
			(net "M_I_CPU0_SA_CA<4>")
		)
		(pad "BA20" smd circle
			(at -16.299942 -4.409948 180)
			(size 0.450088 0.450088)
			(layers "F.Cu" "F.Mask" "F.Paste")
			(net "GND")
		)
		(pad "BA21" smd circle
			(at -15.359888 -4.409948 180)
			(size 0.450088 0.450088)
			(layers "F.Cu" "F.Mask" "F.Paste")
			(net "M_I_CPU0_SA_CA<3>")
		)
		(pad "BA22" smd circle
			(at -14.420088 -4.409948 180)
			(size 0.450088 0.450088)
			(layers "F.Cu" "F.Mask" "F.Paste")
			(net "GND")
		)
		(pad "BA23" smd circle
			(at -13.480034 -4.409948 180)
			(size 0.450088 0.450088)
			(layers "F.Cu" "F.Mask" "F.Paste")
			(net "PVDDCR_SOC_P0")
		)
		(pad "BA24" smd circle
			(at -12.53998 -4.409948 180)
			(size 0.450088 0.450088)
			(layers "F.Cu" "F.Mask" "F.Paste")
			(net "GND")
		)
		(pad "BA25" smd circle
			(at -11.599926 -4.409948 180)
			(size 0.450088 0.450088)
			(layers "F.Cu" "F.Mask" "F.Paste")
			(net "PVDDCR_SOC_P0")
		)
		(pad "BA26" smd circle
			(at -10.659872 -4.409948 180)
			(size 0.450088 0.450088)
			(layers "F.Cu" "F.Mask" "F.Paste")
			(net "GND")
		)
		(pad "BA27" smd circle
			(at -9.720072 -4.409948 180)
			(size 0.450088 0.450088)
			(layers "F.Cu" "F.Mask" "F.Paste")
			(net "PVDDCR_SOC_P0")
		)
		(pad "BA28" smd circle
			(at -8.780018 -4.409948 180)
			(size 0.450088 0.450088)
			(layers "F.Cu" "F.Mask" "F.Paste")
			(net "GND")
		)
		(pad "BA48" smd circle
			(at 9.079992 -4.409948 180)
			(size 0.450088 0.450088)
			(layers "F.Cu" "F.Mask" "F.Paste")
			(net "PVDDCR_SOC_P0")
		)
		(pad "BA49" smd circle
			(at 10.020046 -4.409948 180)
			(size 0.450088 0.450088)
			(layers "F.Cu" "F.Mask" "F.Paste")
			(net "GND")
		)
		(pad "BA50" smd circle
			(at 10.9601 -4.409948 180)
			(size 0.450088 0.450088)
			(layers "F.Cu" "F.Mask" "F.Paste")
			(net "PVDD18_S5_P0")
		)
		(pad "BA51" smd circle
			(at 11.8999 -4.409948 180)
			(size 0.450088 0.450088)
			(layers "F.Cu" "F.Mask" "F.Paste")
			(net "GND")
		)
		(pad "BA52" smd circle
			(at 12.839954 -4.409948 180)
			(size 0.450088 0.450088)
			(layers "F.Cu" "F.Mask" "F.Paste")
			(net "PVDD18_S5_P0")
		)
		(pad "BA53" smd circle
			(at 13.780008 -4.409948 180)
			(size 0.450088 0.450088)
			(layers "F.Cu" "F.Mask" "F.Paste")
			(net "GND")
		)
		(pad "BA54" smd circle
			(at 14.720062 -4.409948 180)
			(size 0.450088 0.450088)
			(layers "F.Cu" "F.Mask" "F.Paste")
			(net "PVDD18_S5_P0")
		)
		(pad "BA55" smd circle
			(at 15.660116 -4.409948 180)
			(size 0.450088 0.450088)
			(layers "F.Cu" "F.Mask" "F.Paste")
			(net "M_C_CPU0_SA_CA<3>")
		)
		(pad "BA56" smd circle
			(at 16.599916 -4.409948 180)
			(size 0.450088 0.450088)
			(layers "F.Cu" "F.Mask" "F.Paste")
			(net "GND")
		)
		(pad "BA57" smd circle
			(at 17.53997 -4.409948 180)
			(size 0.450088 0.450088)
			(layers "F.Cu" "F.Mask" "F.Paste")
			(net "M_C_CPU0_SA_CA<4>")
		)
		(pad "BA58" smd circle
			(at 18.480024 -4.409948 180)
			(size 0.450088 0.450088)
			(layers "F.Cu" "F.Mask" "F.Paste")
			(net "PVDDIO_P0")
		)
		(pad "BA59" smd circle
			(at 19.420078 -4.409948 180)
			(size 0.450088 0.450088)
			(layers "F.Cu" "F.Mask" "F.Paste")
			(net "M_D_CPU0_SA_CA<3>")
		)
		(pad "BA60" smd circle
			(at 20.359878 -4.409948 180)
			(size 0.450088 0.450088)
			(layers "F.Cu" "F.Mask" "F.Paste")
			(net "M_D_CPU0_SA_CA<4>")
		)
		(pad "BA61" smd circle
			(at 21.299932 -4.409948 180)
			(size 0.450088 0.450088)
			(layers "F.Cu" "F.Mask" "F.Paste")
			(net "GND")
		)
		(pad "BA62" smd circle
			(at 22.239986 -4.409948 180)
			(size 0.450088 0.450088)
			(layers "F.Cu" "F.Mask" "F.Paste")
			(net "M_B_CPU0_SA_CA<3>")
		)
		(pad "BA63" smd circle
			(at 23.18004 -4.409948 180)
			(size 0.450088 0.450088)
			(layers "F.Cu" "F.Mask" "F.Paste")
			(net "GND")
		)
		(pad "BA64" smd circle
			(at 24.120094 -4.409948 180)
			(size 0.450088 0.450088)
			(layers "F.Cu" "F.Mask" "F.Paste")
			(net "M_B_CPU0_SA_CA<4>")
		)
		(pad "BA65" smd circle
			(at 25.059894 -4.409948 180)
			(size 0.450088 0.450088)
			(layers "F.Cu" "F.Mask" "F.Paste")
			(net "PVDDIO_P0")
		)
		(pad "BA66" smd circle
			(at 25.999948 -4.409948 180)
			(size 0.450088 0.450088)
			(layers "F.Cu" "F.Mask" "F.Paste")
			(net "M_F_CPU0_SA_CA<3>")
		)
		(pad "BA67" smd circle
			(at 26.940002 -4.409948 180)
			(size 0.450088 0.450088)
			(layers "F.Cu" "F.Mask" "F.Paste")
			(net "M_F_CPU0_SA_CA<4>")
		)
		(pad "BA68" smd circle
			(at 27.880056 -4.409948 180)
			(size 0.450088 0.450088)
			(layers "F.Cu" "F.Mask" "F.Paste")
			(net "GND")
		)
		(pad "BA69" smd circle
			(at 28.82011 -4.409948 180)
			(size 0.450088 0.450088)
			(layers "F.Cu" "F.Mask" "F.Paste")
			(net "M_E_CPU0_SA_CA<3>")
		)
		(pad "BA70" smd circle
			(at 29.75991 -4.409948 180)
			(size 0.450088 0.450088)
			(layers "F.Cu" "F.Mask" "F.Paste")
			(net "GND")
		)
		(pad "BA71" smd circle
			(at 30.699964 -4.409948 180)
			(size 0.450088 0.450088)
			(layers "F.Cu" "F.Mask" "F.Paste")
			(net "M_E_CPU0_SA_CA<4>")
		)
		(pad "BA72" smd circle
			(at 31.640018 -4.409948 180)
			(size 0.450088 0.450088)
			(layers "F.Cu" "F.Mask" "F.Paste")
			(net "PVDDIO_P0")
		)
		(pad "BA73" smd circle
			(at 32.580072 -4.409948 180)
			(size 0.450088 0.450088)
			(layers "F.Cu" "F.Mask" "F.Paste")
			(net "M_A_CPU0_SA_CA<3>")
		)
		(pad "BA74" smd circle
			(at 33.519872 -4.409948 180)
			(size 0.450088 0.450088)
			(layers "F.Cu" "F.Mask" "F.Paste")
			(net "M_A_CPU0_SA_CA<4>")
		)
		(pad "BA75" smd circle
			(at 34.459926 -4.409948 180)
			(size 0.450088 0.450088)
			(layers "F.Cu" "F.Mask" "F.Paste")
			(net "GND")
		)
		(pad "BB2" smd circle
			(at -33.690052 -3.599942 180)
			(size 0.450088 0.450088)
			(layers "F.Cu" "F.Mask" "F.Paste")
			(net "M_G_CPU0_SA_CA<5>")
		)
		(pad "BB3" smd circle
			(at -32.749998 -3.599942 180)
			(size 0.450088 0.450088)
			(layers "F.Cu" "F.Mask" "F.Paste")
			(net "GND")
		)
		(pad "BB4" smd circle
			(at -31.809944 -3.599942 180)
			(size 0.450088 0.450088)
			(layers "F.Cu" "F.Mask" "F.Paste")
			(net "M_G_CPU0_SA_CA<6>")
		)
		(pad "BB5" smd circle
			(at -30.86989 -3.599942 180)
			(size 0.450088 0.450088)
			(layers "F.Cu" "F.Mask" "F.Paste")
			(net "GND")
		)
		(pad "BB6" smd circle
			(at -29.93009 -3.599942 180)
			(size 0.450088 0.450088)
			(layers "F.Cu" "F.Mask" "F.Paste")
			(net "M_K_CPU0_SA_CA<5>")
		)
		(pad "BB7" smd circle
			(at -28.990036 -3.599942 180)
			(size 0.450088 0.450088)
			(layers "F.Cu" "F.Mask" "F.Paste")
			(net "M_K_CPU0_SA_CA<6>")
		)
		(pad "BB8" smd circle
			(at -28.049982 -3.599942 180)
			(size 0.450088 0.450088)
			(layers "F.Cu" "F.Mask" "F.Paste")
			(net "GND")
		)
		(pad "BB9" smd circle
			(at -27.109928 -3.599942 180)
			(size 0.450088 0.450088)
			(layers "F.Cu" "F.Mask" "F.Paste")
			(net "M_L_CPU0_SA_CA<5>")
		)
		(pad "BB10" smd circle
			(at -26.170128 -3.599942 180)
			(size 0.450088 0.450088)
			(layers "F.Cu" "F.Mask" "F.Paste")
			(net "GND")
		)
		(pad "BB11" smd circle
			(at -25.230074 -3.599942 180)
			(size 0.450088 0.450088)
			(layers "F.Cu" "F.Mask" "F.Paste")
			(net "M_L_CPU0_SA_CA<6>")
		)
		(pad "BB12" smd circle
			(at -24.29002 -3.599942 180)
			(size 0.450088 0.450088)
			(layers "F.Cu" "F.Mask" "F.Paste")
			(net "GND")
		)
		(pad "BB13" smd circle
			(at -23.349966 -3.599942 180)
			(size 0.450088 0.450088)
			(layers "F.Cu" "F.Mask" "F.Paste")
			(net "M_H_CPU0_SA_CA<5>")
		)
		(pad "BB14" smd circle
			(at -22.409912 -3.599942 180)
			(size 0.450088 0.450088)
			(layers "F.Cu" "F.Mask" "F.Paste")
			(net "M_H_CPU0_SA_CA<6>")
		)
		(pad "BB15" smd circle
			(at -21.470112 -3.599942 180)
			(size 0.450088 0.450088)
			(layers "F.Cu" "F.Mask" "F.Paste")
			(net "GND")
		)
		(pad "BB16" smd circle
			(at -20.530058 -3.599942 180)
			(size 0.450088 0.450088)
			(layers "F.Cu" "F.Mask" "F.Paste")
			(net "M_J_CPU0_SA_CA<5>")
		)
		(pad "BB17" smd circle
			(at -19.590004 -3.599942 180)
			(size 0.450088 0.450088)
			(layers "F.Cu" "F.Mask" "F.Paste")
			(net "GND")
		)
		(pad "BB18" smd circle
			(at -18.64995 -3.599942 180)
			(size 0.450088 0.450088)
			(layers "F.Cu" "F.Mask" "F.Paste")
			(net "M_J_CPU0_SA_CA<6>")
		)
		(pad "BB19" smd circle
			(at -17.709896 -3.599942 180)
			(size 0.450088 0.450088)
			(layers "F.Cu" "F.Mask" "F.Paste")
			(net "GND")
		)
		(pad "BB20" smd circle
			(at -16.770096 -3.599942 180)
			(size 0.450088 0.450088)
			(layers "F.Cu" "F.Mask" "F.Paste")
			(net "M_I_CPU0_SA_CA<5>")
		)
		(pad "BB21" smd circle
			(at -15.830042 -3.599942 180)
			(size 0.450088 0.450088)
			(layers "F.Cu" "F.Mask" "F.Paste")
			(net "M_I_CPU0_SA_CA<6>")
		)
		(pad "BB22" smd circle
			(at -14.889988 -3.599942 180)
			(size 0.450088 0.450088)
			(layers "F.Cu" "F.Mask" "F.Paste")
			(net "PVDDCR_SOC_P0")
		)
		(pad "BB23" smd circle
			(at -13.949934 -3.599942 180)
			(size 0.450088 0.450088)
			(layers "F.Cu" "F.Mask" "F.Paste")
			(net "GND")
		)
		(pad "BB24" smd circle
			(at -13.00988 -3.599942 180)
			(size 0.450088 0.450088)
			(layers "F.Cu" "F.Mask" "F.Paste")
			(net "PVDDCR_SOC_P0")
		)
		(pad "BB25" smd circle
			(at -12.07008 -3.599942 180)
			(size 0.450088 0.450088)
			(layers "F.Cu" "F.Mask" "F.Paste")
			(net "GND")
		)
		(pad "BB26" smd circle
			(at -11.130026 -3.599942 180)
			(size 0.450088 0.450088)
			(layers "F.Cu" "F.Mask" "F.Paste")
			(net "PVDDCR_SOC_P0")
		)
		(pad "BB27" smd circle
			(at -10.189972 -3.599942 180)
			(size 0.450088 0.450088)
			(layers "F.Cu" "F.Mask" "F.Paste")
			(net "GND")
		)
		(pad "BB28" smd circle
			(at -9.249918 -3.599942 180)
			(size 0.450088 0.450088)
			(layers "F.Cu" "F.Mask" "F.Paste")
			(net "PVDDCR_SOC_P0")
		)
		(pad "BB48" smd circle
			(at 9.549892 -3.599942 180)
			(size 0.450088 0.450088)
			(layers "F.Cu" "F.Mask" "F.Paste")
			(net "GND")
		)
		(pad "BB49" smd circle
			(at 10.489946 -3.599942 180)
			(size 0.450088 0.450088)
			(layers "F.Cu" "F.Mask" "F.Paste")
			(net "PVDDCR_SOC_P0")
		)
		(pad "BB50" smd circle
			(at 11.43 -3.599942 180)
			(size 0.450088 0.450088)
			(layers "F.Cu" "F.Mask" "F.Paste")
			(net "GND")
		)
		(pad "BB51" smd circle
			(at 12.370054 -3.599942 180)
			(size 0.450088 0.450088)
			(layers "F.Cu" "F.Mask" "F.Paste")
			(net "PVDD18_S5_P0")
		)
		(pad "BB52" smd circle
			(at 13.310108 -3.599942 180)
			(size 0.450088 0.450088)
			(layers "F.Cu" "F.Mask" "F.Paste")
			(net "GND")
		)
		(pad "BB53" smd circle
			(at 14.249908 -3.599942 180)
			(size 0.450088 0.450088)
			(layers "F.Cu" "F.Mask" "F.Paste")
			(net "PVDD18_S5_P0")
		)
		(pad "BB54" smd circle
			(at 15.189962 -3.599942 180)
			(size 0.450088 0.450088)
			(layers "F.Cu" "F.Mask" "F.Paste")
			(net "GND")
		)
		(pad "BB55" smd circle
			(at 16.130016 -3.599942 180)
			(size 0.450088 0.450088)
			(layers "F.Cu" "F.Mask" "F.Paste")
			(net "M_C_CPU0_SA_CA<6>")
		)
		(pad "BB56" smd circle
			(at 17.07007 -3.599942 180)
			(size 0.450088 0.450088)
			(layers "F.Cu" "F.Mask" "F.Paste")
			(net "M_C_CPU0_SA_CA<5>")
		)
		(pad "BB57" smd circle
			(at 18.010124 -3.599942 180)
			(size 0.450088 0.450088)
			(layers "F.Cu" "F.Mask" "F.Paste")
			(net "GND")
		)
		(pad "BB58" smd circle
			(at 18.949924 -3.599942 180)
			(size 0.450088 0.450088)
			(layers "F.Cu" "F.Mask" "F.Paste")
			(net "M_D_CPU0_SA_CA<6>")
		)
		(pad "BB59" smd circle
			(at 19.889978 -3.599942 180)
			(size 0.450088 0.450088)
			(layers "F.Cu" "F.Mask" "F.Paste")
			(net "GND")
		)
		(pad "BB60" smd circle
			(at 20.830032 -3.599942 180)
			(size 0.450088 0.450088)
			(layers "F.Cu" "F.Mask" "F.Paste")
			(net "M_D_CPU0_SA_CA<5>")
		)
		(pad "BB61" smd circle
			(at 21.770086 -3.599942 180)
			(size 0.450088 0.450088)
			(layers "F.Cu" "F.Mask" "F.Paste")
			(net "GND")
		)
		(pad "BB62" smd circle
			(at 22.709886 -3.599942 180)
			(size 0.450088 0.450088)
			(layers "F.Cu" "F.Mask" "F.Paste")
			(net "M_B_CPU0_SA_CA<6>")
		)
		(pad "BB63" smd circle
			(at 23.64994 -3.599942 180)
			(size 0.450088 0.450088)
			(layers "F.Cu" "F.Mask" "F.Paste")
			(net "M_B_CPU0_SA_CA<5>")
		)
		(pad "BB64" smd circle
			(at 24.589994 -3.599942 180)
			(size 0.450088 0.450088)
			(layers "F.Cu" "F.Mask" "F.Paste")
			(net "GND")
		)
		(pad "BB65" smd circle
			(at 25.530048 -3.599942 180)
			(size 0.450088 0.450088)
			(layers "F.Cu" "F.Mask" "F.Paste")
			(net "M_F_CPU0_SA_CA<6>")
		)
		(pad "BB66" smd circle
			(at 26.470102 -3.599942 180)
			(size 0.450088 0.450088)
			(layers "F.Cu" "F.Mask" "F.Paste")
			(net "GND")
		)
		(pad "BB67" smd circle
			(at 27.409902 -3.599942 180)
			(size 0.450088 0.450088)
			(layers "F.Cu" "F.Mask" "F.Paste")
			(net "M_F_CPU0_SA_CA<5>")
		)
		(pad "BB68" smd circle
			(at 28.349956 -3.599942 180)
			(size 0.450088 0.450088)
			(layers "F.Cu" "F.Mask" "F.Paste")
			(net "GND")
		)
		(pad "BB69" smd circle
			(at 29.29001 -3.599942 180)
			(size 0.450088 0.450088)
			(layers "F.Cu" "F.Mask" "F.Paste")
			(net "M_E_CPU0_SA_CA<6>")
		)
		(pad "BB70" smd circle
			(at 30.230064 -3.599942 180)
			(size 0.450088 0.450088)
			(layers "F.Cu" "F.Mask" "F.Paste")
			(net "M_E_CPU0_SA_CA<5>")
		)
		(pad "BB71" smd circle
			(at 31.170118 -3.599942 180)
			(size 0.450088 0.450088)
			(layers "F.Cu" "F.Mask" "F.Paste")
			(net "GND")
		)
		(pad "BB72" smd circle
			(at 32.109918 -3.599942 180)
			(size 0.450088 0.450088)
			(layers "F.Cu" "F.Mask" "F.Paste")
			(net "M_A_CPU0_SA_CA<6>")
		)
		(pad "BB73" smd circle
			(at 33.049972 -3.599942 180)
			(size 0.450088 0.450088)
			(layers "F.Cu" "F.Mask" "F.Paste")
			(net "GND")
		)
	)
)
